(kicad_pcb
	(version 20260206)
	(generator "pcbnew")
	(generator_version "10.0")
	(general
		(thickness 1.6)
		(legacy_teardrops no)
	)
	(paper "A4")
	(title_block
		(title "04192023_DAF0TMB3IC0_F0TG_MB_C_brd_V02_OCP.brd")
		(comment 1 "Grand Teton / footprint 2783 of 8354 (U26), pads 760-866 of 6102")
	)
	(layers
		(0 "F.Cu" signal "TOP")
		(4 "In1.Cu" signal "GND")
		(6 "In2.Cu" signal "IN1")
		(8 "In3.Cu" signal "GND1")
		(10 "In4.Cu" signal "IN2")
		(12 "In5.Cu" signal "GND2")
		(14 "In6.Cu" signal "IN3")
		(16 "In7.Cu" signal "GND3")
		(18 "In8.Cu" signal "VCC")
		(20 "In9.Cu" signal "VCC1")
		(22 "In10.Cu" signal "GND4")
		(24 "In11.Cu" signal "IN4")
		(26 "In12.Cu" signal "GND5")
		(28 "In13.Cu" signal "IN5")
		(30 "In14.Cu" signal "GND6")
		(32 "In15.Cu" signal "IN6")
		(34 "In16.Cu" signal "GND7")
		(2 "B.Cu" signal "BOTTOM")
		(9 "F.Adhes" user "F.Adhesive")
		(11 "B.Adhes" user "B.Adhesive")
		(13 "F.Paste" user "Package Geometry/Pastemask Top")
		(15 "B.Paste" user "Package Geometry/Pastemask Bottom")
		(5 "F.SilkS" user "Ref Des/Silkscreen Top")
		(7 "B.SilkS" user "Ref Des/Silkscreen Bottom")
		(1 "F.Mask" user "Board Geometry/Soldermask Top")
		(3 "B.Mask" user "Board Geometry/Soldermask Bottom")
		(17 "Dwgs.User" user "User.Drawings")
		(19 "Cmts.User" user "User.Comments")
		(21 "Eco1.User" user "User.Eco1")
		(23 "Eco2.User" user "User.Eco2")
		(25 "Edge.Cuts" user "Board Geometry/Outline")
		(27 "Margin" user)
		(31 "F.CrtYd" user "Package Geometry/Place Bound Top")
		(29 "B.CrtYd" user "Package Geometry/Place Bound Bottom")
		(35 "F.Fab" user "Ref Des/Assembly Top")
		(33 "B.Fab" user "Ref Des/Assembly Bottom")
	)
	(footprint ""
		(layer "F.Cu")
		(at 111.927894 -258.880356 180)
		(property "Reference" "U26"
			(at -45.05579 -61.794136 0)
			(unlocked yes)
			(layer "F.SilkS")
			(effects
				(font
					(size 0.7874 0.5842)
					(thickness 0.1524)
				)
			)
		)
		(property "Value" ""
			(at 0 0 180)
			(layer "F.Fab")
			(effects
				(font
					(size 1.27 1.27)
				)
			)
		)
		(duplicate_pad_numbers_are_jumpers no)
		(pad "AK52" smd circle
			(at 13.310108 -13.320014 180)
			(size 0.450088 0.450088)
			(layers "F.Cu" "F.Mask" "F.Paste")
			(net "PVDDCR_CPU0_P1")
		)
		(pad "AK53" smd circle
			(at 14.249908 -13.320014 180)
			(size 0.450088 0.450088)
			(layers "F.Cu" "F.Mask" "F.Paste")
			(net "PVDDCR_CPU0_P1")
		)
		(pad "AK54" smd circle
			(at 15.189962 -13.320014 180)
			(size 0.450088 0.450088)
			(layers "F.Cu" "F.Mask" "F.Paste")
			(net "GND")
		)
		(pad "AK55" smd circle
			(at 16.130016 -13.320014 180)
			(size 0.450088 0.450088)
			(layers "F.Cu" "F.Mask" "F.Paste")
			(net "M_C_CPU1_SA_CB<1>")
		)
		(pad "AK56" smd circle
			(at 17.07007 -13.320014 180)
			(size 0.450088 0.450088)
			(layers "F.Cu" "F.Mask" "F.Paste")
			(net "M_C_CPU1_SA_CB<2>")
		)
		(pad "AK57" smd circle
			(at 18.010124 -13.320014 180)
			(size 0.450088 0.450088)
			(layers "F.Cu" "F.Mask" "F.Paste")
			(net "GND")
		)
		(pad "AK58" smd circle
			(at 18.949924 -13.320014 180)
			(size 0.450088 0.450088)
			(layers "F.Cu" "F.Mask" "F.Paste")
			(net "M_D_CPU1_SA_CB<1>")
		)
		(pad "AK59" smd circle
			(at 19.889978 -13.320014 180)
			(size 0.450088 0.450088)
			(layers "F.Cu" "F.Mask" "F.Paste")
			(net "GND")
		)
		(pad "AK60" smd circle
			(at 20.830032 -13.320014 180)
			(size 0.450088 0.450088)
			(layers "F.Cu" "F.Mask" "F.Paste")
			(net "M_D_CPU1_SA_CB<2>")
		)
		(pad "AK61" smd circle
			(at 21.770086 -13.320014 180)
			(size 0.450088 0.450088)
			(layers "F.Cu" "F.Mask" "F.Paste")
			(net "GND")
		)
		(pad "AK62" smd circle
			(at 22.709886 -13.320014 180)
			(size 0.450088 0.450088)
			(layers "F.Cu" "F.Mask" "F.Paste")
			(net "M_B_CPU1_SA_CB<1>")
		)
		(pad "AK63" smd circle
			(at 23.64994 -13.320014 180)
			(size 0.450088 0.450088)
			(layers "F.Cu" "F.Mask" "F.Paste")
			(net "M_B_CPU1_SA_CB<2>")
		)
		(pad "AK64" smd circle
			(at 24.589994 -13.320014 180)
			(size 0.450088 0.450088)
			(layers "F.Cu" "F.Mask" "F.Paste")
			(net "GND")
		)
		(pad "AK65" smd circle
			(at 25.530048 -13.320014 180)
			(size 0.450088 0.450088)
			(layers "F.Cu" "F.Mask" "F.Paste")
			(net "M_F_CPU1_SA_CB<1>")
		)
		(pad "AK66" smd circle
			(at 26.470102 -13.320014 180)
			(size 0.450088 0.450088)
			(layers "F.Cu" "F.Mask" "F.Paste")
			(net "GND")
		)
		(pad "AK67" smd circle
			(at 27.409902 -13.320014 180)
			(size 0.450088 0.450088)
			(layers "F.Cu" "F.Mask" "F.Paste")
			(net "M_F_CPU1_SA_CB<2>")
		)
		(pad "AK68" smd circle
			(at 28.349956 -13.320014 180)
			(size 0.450088 0.450088)
			(layers "F.Cu" "F.Mask" "F.Paste")
			(net "GND")
		)
		(pad "AK69" smd circle
			(at 29.29001 -13.320014 180)
			(size 0.450088 0.450088)
			(layers "F.Cu" "F.Mask" "F.Paste")
			(net "M_E_CPU1_SA_CB<1>")
		)
		(pad "AK70" smd circle
			(at 30.230064 -13.320014 180)
			(size 0.450088 0.450088)
			(layers "F.Cu" "F.Mask" "F.Paste")
			(net "M_E_CPU1_SA_CB<2>")
		)
		(pad "AK71" smd circle
			(at 31.170118 -13.320014 180)
			(size 0.450088 0.450088)
			(layers "F.Cu" "F.Mask" "F.Paste")
			(net "GND")
		)
		(pad "AK72" smd circle
			(at 32.109918 -13.320014 180)
			(size 0.450088 0.450088)
			(layers "F.Cu" "F.Mask" "F.Paste")
			(net "M_A_CPU1_SA_CB<1>")
		)
		(pad "AK73" smd circle
			(at 33.049972 -13.320014 180)
			(size 0.450088 0.450088)
			(layers "F.Cu" "F.Mask" "F.Paste")
			(net "GND")
		)
		(pad "AK74" smd circle
			(at 33.990026 -13.320014 180)
			(size 0.450088 0.450088)
			(layers "F.Cu" "F.Mask" "F.Paste")
			(net "M_A_CPU1_SA_CB<2>")
		)
		(pad "AL1" smd circle
			(at -34.159952 -12.510008 180)
			(size 0.450088 0.450088)
			(layers "F.Cu" "F.Mask" "F.Paste")
			(net "GND")
		)
		(pad "AL2" smd circle
			(at -33.219898 -12.510008 180)
			(size 0.450088 0.450088)
			(layers "F.Cu" "F.Mask" "F.Paste")
			(net "M_G_CPU1_SA_DQS_DP<4>")
		)
		(pad "AL3" smd circle
			(at -32.280098 -12.510008 180)
			(size 0.450088 0.450088)
			(layers "F.Cu" "F.Mask" "F.Paste")
			(net "M_G_CPU1_SA_CB<3>")
		)
		(pad "AL4" smd circle
			(at -31.340044 -12.510008 180)
			(size 0.450088 0.450088)
			(layers "F.Cu" "F.Mask" "F.Paste")
			(net "GND")
		)
		(pad "AL5" smd circle
			(at -30.39999 -12.510008 180)
			(size 0.450088 0.450088)
			(layers "F.Cu" "F.Mask" "F.Paste")
			(net "M_K_CPU1_SA_DQS_DP<4>")
		)
		(pad "AL6" smd circle
			(at -29.459936 -12.510008 180)
			(size 0.450088 0.450088)
			(layers "F.Cu" "F.Mask" "F.Paste")
			(net "GND")
		)
		(pad "AL7" smd circle
			(at -28.519882 -12.510008 180)
			(size 0.450088 0.450088)
			(layers "F.Cu" "F.Mask" "F.Paste")
			(net "M_K_CPU1_SA_CB<3>")
		)
		(pad "AL8" smd circle
			(at -27.580082 -12.510008 180)
			(size 0.450088 0.450088)
			(layers "F.Cu" "F.Mask" "F.Paste")
			(net "GND")
		)
		(pad "AL9" smd circle
			(at -26.640028 -12.510008 180)
			(size 0.450088 0.450088)
			(layers "F.Cu" "F.Mask" "F.Paste")
			(net "M_L_CPU1_SA_DQS_DP<4>")
		)
		(pad "AL10" smd circle
			(at -25.699974 -12.510008 180)
			(size 0.450088 0.450088)
			(layers "F.Cu" "F.Mask" "F.Paste")
			(net "M_L_CPU1_SA_CB<3>")
		)
		(pad "AL11" smd circle
			(at -24.75992 -12.510008 180)
			(size 0.450088 0.450088)
			(layers "F.Cu" "F.Mask" "F.Paste")
			(net "GND")
		)
		(pad "AL12" smd circle
			(at -23.82012 -12.510008 180)
			(size 0.450088 0.450088)
			(layers "F.Cu" "F.Mask" "F.Paste")
			(net "M_H_CPU1_SA_DQS_DP<4>")
		)
		(pad "AL13" smd circle
			(at -22.880066 -12.510008 180)
			(size 0.450088 0.450088)
			(layers "F.Cu" "F.Mask" "F.Paste")
			(net "GND")
		)
		(pad "AL14" smd circle
			(at -21.940012 -12.510008 180)
			(size 0.450088 0.450088)
			(layers "F.Cu" "F.Mask" "F.Paste")
			(net "M_H_CPU1_SA_CB<3>")
		)
		(pad "AL15" smd circle
			(at -20.999958 -12.510008 180)
			(size 0.450088 0.450088)
			(layers "F.Cu" "F.Mask" "F.Paste")
			(net "GND")
		)
		(pad "AL16" smd circle
			(at -20.059904 -12.510008 180)
			(size 0.450088 0.450088)
			(layers "F.Cu" "F.Mask" "F.Paste")
			(net "M_J_CPU1_SA_DQS_DP<4>")
		)
		(pad "AL17" smd circle
			(at -19.120104 -12.510008 180)
			(size 0.450088 0.450088)
			(layers "F.Cu" "F.Mask" "F.Paste")
			(net "M_J_CPU1_SA_CB<3>")
		)
		(pad "AL18" smd circle
			(at -18.18005 -12.510008 180)
			(size 0.450088 0.450088)
			(layers "F.Cu" "F.Mask" "F.Paste")
			(net "GND")
		)
		(pad "AL19" smd circle
			(at -17.239996 -12.510008 180)
			(size 0.450088 0.450088)
			(layers "F.Cu" "F.Mask" "F.Paste")
			(net "M_I_CPU1_SA_DQS_DP<4>")
		)
		(pad "AL20" smd circle
			(at -16.299942 -12.510008 180)
			(size 0.450088 0.450088)
			(layers "F.Cu" "F.Mask" "F.Paste")
			(net "GND")
		)
		(pad "AL21" smd circle
			(at -15.359888 -12.510008 180)
			(size 0.450088 0.450088)
			(layers "F.Cu" "F.Mask" "F.Paste")
			(net "M_I_CPU1_SA_CB<3>")
		)
		(pad "AL22" smd circle
			(at -14.420088 -12.510008 180)
			(size 0.450088 0.450088)
			(layers "F.Cu" "F.Mask" "F.Paste")
			(net "GND")
		)
		(pad "AL23" smd circle
			(at -13.480034 -12.510008 180)
			(size 0.450088 0.450088)
			(layers "F.Cu" "F.Mask" "F.Paste")
			(net "GMI_CPU0_G1_CPU1_G3_TX_DN<15>")
		)
		(pad "AL24" smd circle
			(at -12.53998 -12.510008 180)
			(size 0.450088 0.450088)
			(layers "F.Cu" "F.Mask" "F.Paste")
			(net "GMI_CPU0_G1_CPU1_G3_TX_DP<15>")
		)
		(pad "AL25" smd circle
			(at -11.599926 -12.510008 180)
			(size 0.450088 0.450088)
			(layers "F.Cu" "F.Mask" "F.Paste")
			(net "GND")
		)
		(pad "AL26" smd circle
			(at -10.659872 -12.510008 180)
			(size 0.450088 0.450088)
			(layers "F.Cu" "F.Mask" "F.Paste")
			(net "GMI_CPU0_G1_CPU1_G3_TX_DN<12>")
		)
		(pad "AL27" smd circle
			(at -9.720072 -12.510008 180)
			(size 0.450088 0.450088)
			(layers "F.Cu" "F.Mask" "F.Paste")
			(net "GMI_CPU0_G1_CPU1_G3_TX_DP<12>")
		)
		(pad "AL28" smd circle
			(at -8.780018 -12.510008 180)
			(size 0.450088 0.450088)
			(layers "F.Cu" "F.Mask" "F.Paste")
			(net "GND")
		)
		(pad "AL29" smd circle
			(at -7.839964 -12.510008 180)
			(size 0.450088 0.450088)
			(layers "F.Cu" "F.Mask" "F.Paste")
			(net "GMI_CPU0_G1_CPU1_G3_TX_DN<9>")
		)
		(pad "AL30" smd circle
			(at -6.89991 -12.510008 180)
			(size 0.450088 0.450088)
			(layers "F.Cu" "F.Mask" "F.Paste")
			(net "GMI_CPU0_G1_CPU1_G3_TX_DP<9>")
		)
		(pad "AL31" smd circle
			(at -5.96011 -12.510008 180)
			(size 0.450088 0.450088)
			(layers "F.Cu" "F.Mask" "F.Paste")
			(net "GND")
		)
		(pad "AL32" smd circle
			(at -5.020056 -12.510008 180)
			(size 0.450088 0.450088)
			(layers "F.Cu" "F.Mask" "F.Paste")
			(net "GMI_CPU0_G1_CPU1_G3_TX_DN<6>")
		)
		(pad "AL33" smd circle
			(at -4.080002 -12.510008 180)
			(size 0.450088 0.450088)
			(layers "F.Cu" "F.Mask" "F.Paste")
			(net "GMI_CPU0_G1_CPU1_G3_TX_DP<6>")
		)
		(pad "AL34" smd circle
			(at -3.139948 -12.510008 180)
			(size 0.450088 0.450088)
			(layers "F.Cu" "F.Mask" "F.Paste")
			(net "GND")
		)
		(pad "AL35" smd circle
			(at -2.199894 -12.510008 180)
			(size 0.450088 0.450088)
			(layers "F.Cu" "F.Mask" "F.Paste")
			(net "PVDDCR_CPU0_P1")
		)
		(pad "AL36" smd circle
			(at -1.260094 -12.510008 180)
			(size 0.450088 0.450088)
			(layers "F.Cu" "F.Mask" "F.Paste")
			(net "PVDDCR_CPU0_P1")
		)
		(pad "AL40" smd circle
			(at 1.560068 -12.510008 180)
			(size 0.450088 0.450088)
			(layers "F.Cu" "F.Mask" "F.Paste")
			(net "PVDDCR_CPU0_P1")
		)
		(pad "AL41" smd circle
			(at 2.500122 -12.510008 180)
			(size 0.450088 0.450088)
			(layers "F.Cu" "F.Mask" "F.Paste")
			(net "PVDDCR_CPU0_P1")
		)
		(pad "AL42" smd circle
			(at 3.439922 -12.510008 180)
			(size 0.450088 0.450088)
			(layers "F.Cu" "F.Mask" "F.Paste")
			(net "GND")
		)
		(pad "AL43" smd circle
			(at 4.379976 -12.510008 180)
			(size 0.450088 0.450088)
			(layers "F.Cu" "F.Mask" "F.Paste")
			(net "P5E_CPU1_G1_TX_DP<6>")
		)
		(pad "AL44" smd circle
			(at 5.32003 -12.510008 180)
			(size 0.450088 0.450088)
			(layers "F.Cu" "F.Mask" "F.Paste")
			(net "P5E_CPU1_G1_TX_DN<6>")
		)
		(pad "AL45" smd circle
			(at 6.260084 -12.510008 180)
			(size 0.450088 0.450088)
			(layers "F.Cu" "F.Mask" "F.Paste")
			(net "GND")
		)
		(pad "AL46" smd circle
			(at 7.199884 -12.510008 180)
			(size 0.450088 0.450088)
			(layers "F.Cu" "F.Mask" "F.Paste")
			(net "P5E_CPU1_G1_TX_DP<9>")
		)
		(pad "AL47" smd circle
			(at 8.139938 -12.510008 180)
			(size 0.450088 0.450088)
			(layers "F.Cu" "F.Mask" "F.Paste")
			(net "P5E_CPU1_G1_TX_DN<9>")
		)
		(pad "AL48" smd circle
			(at 9.079992 -12.510008 180)
			(size 0.450088 0.450088)
			(layers "F.Cu" "F.Mask" "F.Paste")
			(net "GND")
		)
		(pad "AL49" smd circle
			(at 10.020046 -12.510008 180)
			(size 0.450088 0.450088)
			(layers "F.Cu" "F.Mask" "F.Paste")
			(net "P5E_CPU1_G1_TX_DP<12>")
		)
		(pad "AL50" smd circle
			(at 10.9601 -12.510008 180)
			(size 0.450088 0.450088)
			(layers "F.Cu" "F.Mask" "F.Paste")
			(net "P5E_CPU1_G1_TX_DN<12>")
		)
		(pad "AL51" smd circle
			(at 11.8999 -12.510008 180)
			(size 0.450088 0.450088)
			(layers "F.Cu" "F.Mask" "F.Paste")
			(net "GND")
		)
		(pad "AL52" smd circle
			(at 12.839954 -12.510008 180)
			(size 0.450088 0.450088)
			(layers "F.Cu" "F.Mask" "F.Paste")
			(net "P5E_CPU1_G1_TX_DP<15>")
		)
		(pad "AL53" smd circle
			(at 13.780008 -12.510008 180)
			(size 0.450088 0.450088)
			(layers "F.Cu" "F.Mask" "F.Paste")
			(net "P5E_CPU1_G1_TX_DN<15>")
		)
		(pad "AL54" smd circle
			(at 14.720062 -12.510008 180)
			(size 0.450088 0.450088)
			(layers "F.Cu" "F.Mask" "F.Paste")
			(net "GND")
		)
		(pad "AL55" smd circle
			(at 15.660116 -12.510008 180)
			(size 0.450088 0.450088)
			(layers "F.Cu" "F.Mask" "F.Paste")
			(net "M_C_CPU1_SA_CB<3>")
		)
		(pad "AL56" smd circle
			(at 16.599916 -12.510008 180)
			(size 0.450088 0.450088)
			(layers "F.Cu" "F.Mask" "F.Paste")
			(net "GND")
		)
		(pad "AL57" smd circle
			(at 17.53997 -12.510008 180)
			(size 0.450088 0.450088)
			(layers "F.Cu" "F.Mask" "F.Paste")
			(net "M_C_CPU1_SA_DQS_DP<4>")
		)
		(pad "AL58" smd circle
			(at 18.480024 -12.510008 180)
			(size 0.450088 0.450088)
			(layers "F.Cu" "F.Mask" "F.Paste")
			(net "GND")
		)
		(pad "AL59" smd circle
			(at 19.420078 -12.510008 180)
			(size 0.450088 0.450088)
			(layers "F.Cu" "F.Mask" "F.Paste")
			(net "M_D_CPU1_SA_CB<3>")
		)
		(pad "AL60" smd circle
			(at 20.359878 -12.510008 180)
			(size 0.450088 0.450088)
			(layers "F.Cu" "F.Mask" "F.Paste")
			(net "M_D_CPU1_SA_DQS_DP<4>")
		)
		(pad "AL61" smd circle
			(at 21.299932 -12.510008 180)
			(size 0.450088 0.450088)
			(layers "F.Cu" "F.Mask" "F.Paste")
			(net "GND")
		)
		(pad "AL62" smd circle
			(at 22.239986 -12.510008 180)
			(size 0.450088 0.450088)
			(layers "F.Cu" "F.Mask" "F.Paste")
			(net "M_B_CPU1_SA_CB<3>")
		)
		(pad "AL63" smd circle
			(at 23.18004 -12.510008 180)
			(size 0.450088 0.450088)
			(layers "F.Cu" "F.Mask" "F.Paste")
			(net "GND")
		)
		(pad "AL64" smd circle
			(at 24.120094 -12.510008 180)
			(size 0.450088 0.450088)
			(layers "F.Cu" "F.Mask" "F.Paste")
			(net "M_B_CPU1_SA_DQS_DP<4>")
		)
		(pad "AL65" smd circle
			(at 25.059894 -12.510008 180)
			(size 0.450088 0.450088)
			(layers "F.Cu" "F.Mask" "F.Paste")
			(net "GND")
		)
		(pad "AL66" smd circle
			(at 25.999948 -12.510008 180)
			(size 0.450088 0.450088)
			(layers "F.Cu" "F.Mask" "F.Paste")
			(net "M_F_CPU1_SA_CB<3>")
		)
		(pad "AL67" smd circle
			(at 26.940002 -12.510008 180)
			(size 0.450088 0.450088)
			(layers "F.Cu" "F.Mask" "F.Paste")
			(net "M_F_CPU1_SA_DQS_DP<4>")
		)
		(pad "AL68" smd circle
			(at 27.880056 -12.510008 180)
			(size 0.450088 0.450088)
			(layers "F.Cu" "F.Mask" "F.Paste")
			(net "GND")
		)
		(pad "AL69" smd circle
			(at 28.82011 -12.510008 180)
			(size 0.450088 0.450088)
			(layers "F.Cu" "F.Mask" "F.Paste")
			(net "M_E_CPU1_SA_CB<3>")
		)
		(pad "AL70" smd circle
			(at 29.75991 -12.510008 180)
			(size 0.450088 0.450088)
			(layers "F.Cu" "F.Mask" "F.Paste")
			(net "GND")
		)
		(pad "AL71" smd circle
			(at 30.699964 -12.510008 180)
			(size 0.450088 0.450088)
			(layers "F.Cu" "F.Mask" "F.Paste")
			(net "M_E_CPU1_SA_DQS_DP<4>")
		)
		(pad "AL72" smd circle
			(at 31.640018 -12.510008 180)
			(size 0.450088 0.450088)
			(layers "F.Cu" "F.Mask" "F.Paste")
			(net "GND")
		)
		(pad "AL73" smd circle
			(at 32.580072 -12.510008 180)
			(size 0.450088 0.450088)
			(layers "F.Cu" "F.Mask" "F.Paste")
			(net "M_A_CPU1_SA_CB<3>")
		)
		(pad "AL74" smd circle
			(at 33.519872 -12.510008 180)
			(size 0.450088 0.450088)
			(layers "F.Cu" "F.Mask" "F.Paste")
			(net "M_A_CPU1_SA_DQS_DP<4>")
		)
		(pad "AL75" smd circle
			(at 34.459926 -12.510008 180)
			(size 0.450088 0.450088)
			(layers "F.Cu" "F.Mask" "F.Paste")
			(net "GND")
		)
		(pad "AM2" smd circle
			(at -33.690052 -11.700002 180)
			(size 0.450088 0.450088)
			(layers "F.Cu" "F.Mask" "F.Paste")
			(net "M_G_CPU1_SA_DQS_DN<4>")
		)
		(pad "AM3" smd circle
			(at -32.749998 -11.700002 180)
			(size 0.450088 0.450088)
			(layers "F.Cu" "F.Mask" "F.Paste")
			(net "GND")
		)
		(pad "AM4" smd circle
			(at -31.809944 -11.700002 180)
			(size 0.450088 0.450088)
			(layers "F.Cu" "F.Mask" "F.Paste")
			(net "M_G_CPU1_SA_DQS_DN<9>")
		)
		(pad "AM5" smd circle
			(at -30.86989 -11.700002 180)
			(size 0.450088 0.450088)
			(layers "F.Cu" "F.Mask" "F.Paste")
			(net "PVDDCR_SOC_P1")
		)
		(pad "AM6" smd circle
			(at -29.93009 -11.700002 180)
			(size 0.450088 0.450088)
			(layers "F.Cu" "F.Mask" "F.Paste")
			(net "M_K_CPU1_SA_DQS_DN<4>")
		)
		(pad "AM7" smd circle
			(at -28.990036 -11.700002 180)
			(size 0.450088 0.450088)
			(layers "F.Cu" "F.Mask" "F.Paste")
			(net "M_K_CPU1_SA_DQS_DN<9>")
		)
		(pad "AM8" smd circle
			(at -28.049982 -11.700002 180)
			(size 0.450088 0.450088)
			(layers "F.Cu" "F.Mask" "F.Paste")
			(net "GND")
		)
		(pad "AM9" smd circle
			(at -27.109928 -11.700002 180)
			(size 0.450088 0.450088)
			(layers "F.Cu" "F.Mask" "F.Paste")
			(net "M_L_CPU1_SA_DQS_DN<4>")
		)
		(pad "AM10" smd circle
			(at -26.170128 -11.700002 180)
			(size 0.450088 0.450088)
			(layers "F.Cu" "F.Mask" "F.Paste")
			(net "GND")
		)
		(pad "AM11" smd circle
			(at -25.230074 -11.700002 180)
			(size 0.450088 0.450088)
			(layers "F.Cu" "F.Mask" "F.Paste")
			(net "M_L_CPU1_SA_DQS_DN<9>")
		)
		(pad "AM12" smd circle
			(at -24.29002 -11.700002 180)
			(size 0.450088 0.450088)
			(layers "F.Cu" "F.Mask" "F.Paste")
			(net "PVDDCR_SOC_P1")
		)
		(pad "AM13" smd circle
			(at -23.349966 -11.700002 180)
			(size 0.450088 0.450088)
			(layers "F.Cu" "F.Mask" "F.Paste")
			(net "M_H_CPU1_SA_DQS_DN<4>")
		)
	)
)
